FILE_TYPE = CONNECTIVITY;
{Allegro Design Entry HDL 17.2-2016 S081 (4005846) 1/11/2022}
"PAGE_NUMBER" = 283;
0"NC";
1"PVCCFA_EHV_CPU1_PVCC";
2"PVCCD_HV_CPU1\g";
3"PVCCD_HV_CPU1\g";
4"SW_P12V_PVCCINFAON_CPU1_FLT\g";
5"GND\g";
6"GND\g";
7"GND\g";
8"GND\g";
9"GND\g";
10"GND\g";
11"GND\g";
12"GND\g";
13"SW_PVCCD_HV_CPU1_BOOT1_R";
14"SW_PVCCD_HV_CPU1_BOOT1"CDS_PHYS_NET_NAME"SW_PVCCD_HV_CPU1_BOOT1";
15"PVCCD_HV_CPU1_VDD1";
16"PVCCD_HV_CPU1_VOS";
17"SW_PVCCD_HV_CPU1_SW1";
18"SW_PVCCD_HV_CPU1_BOOTR1"CDS_PHYS_NET_NAME"SW_PVCCD_HV_CPU1_BOOTR1";
19"PVCCD_HV_CPU1_ACSP1";
20"PVCCD_HV_CPU1_ATSEN";
21"PVCCD_HV_CPU1_APWM1";
22"PVCCD_HV_CPU1_VREF"CDS_PHYS_NET_NAME"PVCCD_HV_CPU1_VREF";
23"PVCCD_HV_CPU1_LSET1";
%"UNIVERSAL_GND"
"1","(-8650,2825)","0","logical_power","I1";
;
HDL_POWER"GND"
CDS_LIB"logical_power";
"A"5;
%"ISL99390FRZTR5935"
"1","(-6525,3625)","0","pure_quanta","I10";
;
PART_NUMBER"AL099390004"
VALUE"ISL99390FRZ-TR5935"
PART_TYPE"SMLF"
MATERIAL"IC"
LOCATION"PU17"
SEC_TYPE""
CDS_LMAN_SYM_OUTLINE"-300,700,250,-650"
NEEDS_NO_SIZE"TRUE"
CDS_LIB"pure_quanta"
SEC"1";
"PGND2"
$PN"7_9-20_24"8;
"GL2"
$PN"41"0;
"GL1"
$PN"6"0;
"DNC"
$PN"31"0;
"EN"
$PN"35"15;
"PGND3"
$PN"40"8;
"VOS"
$PN"1"16;
"VIN2"
$PN"30"4;
"PGND1"
$PN"5"8;
"SW"
$PN"10_19"17;
"LSET"
$PN"37"23;
"IOUT"
$PN"38"19;
"TOUT_FLT"
$PN"36"20;
"PVCC"
$PN"4"1;
"PHASE"
$PN"32"18;
"VIN1"
$PN"25_29"4;
"BOOT"
$PN"33"14;
"AGND"
$PN"2"8;
"VCC"
$PN"3"15;
"REFIN"
$PN"39"22;
"PWM"
$PN"34"21;
%"UNIVERSAL_GND"
"1","(-5875,2900)","0","logical_power","I11";
;
HDL_POWER"GND"
CDS_LIB"logical_power";
"A"8;
%"Q_RES"
"1","(-4950,3375)","0","pure_quanta","I12";
;
PART_NUMBER"CS00002JB13"
MATERIAL"CHIP"
VALUE"0"
TOLERANCE"5%"
WATTAGE"1/16W"
PACK_TYPE"0402LF"
LOCATION"PR1805"
CDS_LIB"pure_quanta"
$SEC"1"
CDS_SEC"1";
"B"
$PN"2"3;
"A"
$PN"1"16;
%"Q_CAP"
"1","(-4500,3900)","2","pure_quanta","I13";
;
PART_NUMBER"CH4106K1B01"
MATERIAL"X7R"
VALUE"100NF"
VOLTAGE"50V"
PACK_TYPE"C0402"
TOLERANCE"10%"
LOCATION"PC376"
CDS_LIB"pure_quanta"
$SEC"1"
CDS_SEC"1";
"B"
$PN"2"18;
"A"
$PN"1"13;
%"Q_INDUCTOR"
"1","(-4025,3650)","0","pure_quanta","I14";
;
PART_NUMBER"CV+12^0EZ03"
PACK_TYPE"SMLF"
MATERIAL"IND"
VALUE"120NH/69A"
LOCATION"PL17"
NEEDS_NO_SIZE"TRUE"
CDS_LIB"pure_quanta"
$SEC"1"
CDS_SEC"1";
"1"
$PN"1"17;
"2"
$PN"2"3;
%"Q_CAP"
"1","(-8050,4075)","0","pure_quanta","I15";
;
PART_NUMBER"CH5222KEB01"
VALUE"2.2UF"
PACK_TYPE"C0402"
MATERIAL"X6S"
VOLTAGE"10V"
TOLERANCE"10%"
LOCATION"PC373"
CDS_LIB"pure_quanta"
LOCATION"PC373"
$SEC"1"
CDS_SEC"1";
"B"
$PN"2"7;
"A"
$PN"1"15;
%"Q_RES"
"2","(-8050,4475)","0","pure_quanta","I16";
;
PART_NUMBER"CS-2202FB01"
PACK_TYPE"0402LF"
WATTAGE"1/16W"
MATERIAL"CHIP"
VALUE"2.2"
TOLERANCE"1%"
LOCATION"PR200"
CDS_LIB"pure_quanta"
LOCATION"PR200"
$SEC"1"
CDS_SEC"1";
"A"
$PN"1"1;
"B"
$PN"2"15;
%"VCC15"
"1","(-8050,4925)","0","logical_power","I17";
;
HDL_POWER"PVCCFA_EHV_CPU1_PVCC"
CDS_LIB"logical_power";
"A"1;
%"Q_CAP"
"1","(-7500,4525)","0","pure_quanta","I18";
;
PART_NUMBER"CH5222KEB01"
VALUE"2.2UF"
MATERIAL"X6S"
VOLTAGE"10V"
TOLERANCE"10%"
PACK_TYPE"C0402"
LOCATION"PC2951"
CDS_LIB"pure_quanta"
$SEC"1"
CDS_SEC"1";
"B"
$PN"2"9;
"A"
$PN"1"1;
%"UNIVERSAL_GND"
"1","(-7500,4325)","0","logical_power","I19";
;
HDL_POWER"GND"
CDS_LIB"logical_power";
"A"9;
%"UNIVERSAL_GND"
"1","(-8850,3350)","0","logical_power","I2";
;
HDL_POWER"GND"
CDS_LIB"logical_power";
"A"6;
%"Q_CAP"
"1","(-5725,4525)","0","pure_quanta","I20";
;
PART_NUMBER"TMP_QCH2336K1B12"
MATERIAL"X7R"
TOLERANCE"10%"
VALUE"3300PF"
VOLTAGE"50V"
PACK_TYPE"0402"
LOCATION"PC374"
CDS_LIB"pure_quanta"
LOCATION"PC374"
$SEC"1"
CDS_SEC"1";
"B"
$PN"2"12;
"A"
$PN"1"4;
%"Q_RES"
"1","(-5225,4075)","0","pure_quanta","I21";
;
PART_NUMBER"CS-3302FB01"
WATTAGE"1/16W"
VALUE"3.3"
TOLERANCE"1%"
PACK_TYPE"0402LF"
MATERIAL"CHIP"
LOCATION"PR1804"
CDS_LIB"pure_quanta"
$SEC"1"
CDS_SEC"1";
"B"
$PN"2"13;
"A"
$PN"1"14;
%"Q_CAP"
"1","(-5325,4525)","0","pure_quanta","I22";
;
PART_NUMBER"CH5103KEB01"
MATERIAL"X6S"
TOLERANCE"10%"
VALUE"1UF"
VOLTAGE"16V"
PACK_TYPE"C0402"
LOCATION"PC375"
CDS_LIB"pure_quanta"
LOCATION"PC375"
$SEC"1"
CDS_SEC"1";
"B"
$PN"2"12;
"A"
$PN"1"4;
%"Q_CAP"
"1","(-4925,4525)","0","pure_quanta","I23";
;
PART_NUMBER"CH6223MEA01"
TOLERANCE"20%"
MATERIAL"X6S"
VALUE"22UF"
VOLTAGE"16V"
PACK_TYPE"C0805"
LOCATION"PC377"
CDS_LIB"pure_quanta"
LOCATION"PC377"
$SEC"1"
CDS_SEC"1";
"B"
$PN"2"12;
"A"
$PN"1"4;
%"Q_CAP"
"1","(-4525,4525)","0","pure_quanta","I24";
;
PART_NUMBER"CH6223MEA01"
TOLERANCE"20%"
PACK_TYPE"C0805"
MATERIAL"X6S"
VALUE"22UF"
VOLTAGE"16V"
LOCATION"PC378"
CDS_LIB"pure_quanta"
LOCATION"PC378"
$SEC"1"
CDS_SEC"1";
"B"
$PN"2"12;
"A"
$PN"1"4;
%"Q_CAPP"
"1","(-2975,2000)","0","pure_quanta","I25";
;
PART_NUMBER"CH733RY8807"
MATERIAL"SPCAP"
TOLERANCE"35%"
VALUE"330UF"
VOLTAGE"2V"
PACK_TYPE"SMLF"
LOCATION"PC1940"
CDS_LIB"pure_quanta"
$SEC"1"
CDS_SEC"1";
"A"
$PN"1"2;
"B"
$PN"2"10;
%"Q_CAPP"
"1","(-2500,1975)","0","pure_quanta","I26";
;
PART_NUMBER"CC7560JMD16"
PACK_TYPE"THLF"
VALUE"560UF"
TOLERANCE"20%"
MATERIAL"OSCON"
VOLTAGE"2.5V"
LOCATION"PC384"
CDS_LIB"pure_quanta"
LOCATION"PC384"
$SEC"1"
CDS_SEC"1";
"A"
$PN"1"2;
"B"
$PN"2"10;
%"Q_CAP"
"1","(-3425,3425)","0","pure_quanta","I27";
;
PART_NUMBER"CH4106K1B01"
PACK_TYPE"C0402"
TOLERANCE"10%"
VOLTAGE"50V"
VALUE"100NF"
MATERIAL"X7R"
LOCATION"PC379"
CDS_LIB"pure_quanta"
LOCATION"PC379"
$SEC"1"
CDS_SEC"1";
"B"
$PN"2"11;
"A"
$PN"1"3;
%"Q_CAP"
"1","(-3025,3425)","0","pure_quanta","I28";
;
PART_NUMBER"CH622KMEA03"
TOLERANCE"20%"
MATERIAL"X6S"
VOLTAGE"4V"
VALUE"22UF"
PACK_TYPE"C0805"
LOCATION"PC381"
CDS_LIB"pure_quanta"
LOCATION"PC381"
$SEC"1"
CDS_SEC"1";
"B"
$PN"2"11;
"A"
$PN"1"3;
%"Q_CAP"
"1","(-2625,3425)","0","pure_quanta","I29";
;
PART_NUMBER"CH622KMEA03"
TOLERANCE"20%"
MATERIAL"X6S"
VALUE"22UF"
VOLTAGE"4V"
PACK_TYPE"C0805"
LOCATION"PC382"
CDS_LIB"pure_quanta"
LOCATION"PC382"
$SEC"1"
CDS_SEC"1";
"B"
$PN"2"11;
"A"
$PN"1"3;
%"Q_RES"
"2","(-8650,3050)","2","pure_quanta","I3";
;
PART_NUMBER"CS28872FB01"
WATTAGE"1/16W"
MATERIAL"EMPTY"
TOLERANCE"1%"
VALUE"8.87K"
PACK_TYPE"0402LF"
LOCATION"PR1746"
CDS_LIB"pure_quanta"
$SEC"1"
CDS_SEC"1";
"A"
$PN"1"23;
"B"
$PN"2"5;
%"Q_CAP"
"1","(-2200,3425)","0","pure_quanta","I30";
;
PART_NUMBER"CH622KMEA03"
TOLERANCE"20%"
VALUE"22UF"
PACK_TYPE"C0805"
VOLTAGE"4V"
MATERIAL"X6S"
LOCATION"PC2"
CDS_LIB"pure_quanta"
LOCATION"PC2"
$SEC"1"
CDS_SEC"1";
"B"
$PN"2"11;
"A"
$PN"1"3;
%"UNIVERSAL_GND"
"1","(-2000,1650)","0","logical_power","I31";
;
HDL_POWER"GND"
CDS_LIB"logical_power";
"A"10;
%"Q_CAPP"
"1","(-2000,1975)","0","pure_quanta","I32";
;
PART_NUMBER"CC7560JMD16"
PACK_TYPE"THLF"
VALUE"560UF"
TOLERANCE"20%"
MATERIAL"OSCON"
VOLTAGE"2.5V"
LOCATION"PC385"
CDS_LIB"pure_quanta"
LOCATION"PC385"
$SEC"1"
CDS_SEC"1";
"A"
$PN"1"2;
"B"
$PN"2"10;
%"VCC15"
"1","(-2000,2300)","0","logical_power","I33";
;
HDL_POWER"PVCCD_HV_CPU1"
CDS_LIB"logical_power";
"A"2;
%"UNIVERSAL_GND"
"1","(-1750,3050)","0","logical_power","I34";
;
HDL_POWER"GND"
CDS_LIB"logical_power";
"A"11;
%"Q_RES"
"2","(-1750,3425)","0","pure_quanta","I35";
;
PART_NUMBER"CS14992FB06"
PACK_TYPE"0402LF"
MATERIAL"CHIP"
WATTAGE"1/16W"
TOLERANCE"1%"
VALUE"499"
LOCATION"PR4258"
CDS_LIB"pure_quanta"
BOM_COST"VR_PCH"
$SEC"1"
CDS_SEC"1";
"A"
$PN"1"3;
"B"
$PN"2"11;
%"VCC15"
"1","(-1750,3775)","0","logical_power","I36";
;
HDL_POWER"PVCCD_HV_CPU1"
CDS_LIB"logical_power";
"A"3;
%"UNIVERSAL_GND"
"1","(-3925,4100)","0","logical_power","I37";
;
HDL_POWER"GND"
CDS_LIB"logical_power";
"A"12;
%"VCC15"
"1","(-3925,4900)","0","logical_power","I38";
;
HDL_POWER"SW_P12V_PVCCINFAON_CPU1_FLT"
CDS_LIB"logical_power";
"A"4;
%"Q_CAP"
"2","(-7850,3450)","0","pure_quanta","I8";
;
PART_NUMBER"CH4104K1B00"
MATERIAL"X7R"
PACK_TYPE"0402"
VALUE"0.1UF"
VOLTAGE"25V"
TOLERANCE"10%"
LOCATION"PC1371"
CDS_LIB"pure_quanta"
$SEC"1"
CDS_SEC"1";
"A"
$PN"1"6;
"B"
$PN"2"22;
%"UNIVERSAL_GND"
"1","(-8050,3825)","0","logical_power","I9";
;
HDL_POWER"GND"
CDS_LIB"logical_power";
"A"7;
END.
